# T6G (Grand Teton) — schematic netlist excerpt (pin names and nets, part order shuffled) for the footprints in the layout excerpt that follows; sources: Cadence DE-HDL packaged netlist, KiCad conversion of 04192023_DAF0TMB3IC0_F0TG_MB_C_brd_V02_OCP.brd

C80  Q_CAP  0.1UF 25V 10% X7R  pkg 0402  page 182 : A = P3V3_9ZXL045_P0_VDD ; B = GND
C2040  Q_CAP  0.1UF 25V 10% X7R  pkg 0402  page 234 : A = P3V3_AUX_USB_HUB ; B = GND
R1022  Q_RES  200 1% CHIP  pkg 0201LF  page 287 : A = RT_CPU0_P1_SCAN_MODE ; B = GND

(kicad_pcb
	(version 20260206)
	(generator "pcbnew")
	(generator_version "10.0")
	(general
		(thickness 1.6)
		(legacy_teardrops no)
	)
	(paper "A4")
	(title_block
		(title "04192023_DAF0TMB3IC0_F0TG_MB_C_brd_V02_OCP.brd")
		(comment 1 "Grand Teton / footprints 7993-7995 of 8354")
	)
	(layers
		(0 "F.Cu" signal "TOP")
		(4 "In1.Cu" signal "GND")
		(6 "In2.Cu" signal "IN1")
		(8 "In3.Cu" signal "GND1")
		(10 "In4.Cu" signal "IN2")
		(12 "In5.Cu" signal "GND2")
		(14 "In6.Cu" signal "IN3")
		(16 "In7.Cu" signal "GND3")
		(18 "In8.Cu" signal "VCC")
		(20 "In9.Cu" signal "VCC1")
		(22 "In10.Cu" signal "GND4")
		(24 "In11.Cu" signal "IN4")
		(26 "In12.Cu" signal "GND5")
		(28 "In13.Cu" signal "IN5")
		(30 "In14.Cu" signal "GND6")
		(32 "In15.Cu" signal "IN6")
		(34 "In16.Cu" signal "GND7")
		(2 "B.Cu" signal "BOTTOM")
		(9 "F.Adhes" user "F.Adhesive")
		(11 "B.Adhes" user "B.Adhesive")
		(13 "F.Paste" user "Package Geometry/Pastemask Top")
		(15 "B.Paste" user "Package Geometry/Pastemask Bottom")
		(5 "F.SilkS" user "Ref Des/Silkscreen Top")
		(7 "B.SilkS" user "Ref Des/Silkscreen Bottom")
		(1 "F.Mask" user "Board Geometry/Soldermask Top")
		(3 "B.Mask" user "Board Geometry/Soldermask Bottom")
		(17 "Dwgs.User" user "User.Drawings")
		(19 "Cmts.User" user "User.Comments")
		(21 "Eco1.User" user "User.Eco1")
		(23 "Eco2.User" user "User.Eco2")
		(25 "Edge.Cuts" user "Board Geometry/Outline")
		(27 "Margin" user)
		(31 "F.CrtYd" user "Package Geometry/Place Bound Top")
		(29 "B.CrtYd" user "Package Geometry/Place Bound Bottom")
		(35 "F.Fab" user "Ref Des/Assembly Top")
		(33 "B.Fab" user "Ref Des/Assembly Bottom")
	)
	(footprint ""
		(layer "B.Cu")
		(at 286.893 -415.798 -90)
		(property "Reference" "C80"
			(at 0 0 90)
			(layer "B.SilkS")
			(hide yes)
			(effects
				(font
					(size 1.27 1.27)
				)
				(justify mirror)
			)
		)
		(property "Value" ""
			(at 0 0 90)
			(layer "B.Fab")
			(effects
				(font
					(size 1.27 1.27)
				)
				(justify mirror)
			)
		)
		(duplicate_pad_numbers_are_jumpers no)
		(fp_line
			(start -0.7874 0.4064)
			(end 0.7874 0.4064)
			(stroke
				(width 0.1524)
				(type default)
			)
			(layer "B.SilkS")
		)
		(fp_line
			(start 0.7874 0.4064)
			(end 0.7874 -0.4064)
			(stroke
				(width 0.1524)
				(type default)
			)
			(layer "B.SilkS")
		)
		(fp_line
			(start -0.7874 -0.4064)
			(end -0.7874 0.4064)
			(stroke
				(width 0.1524)
				(type default)
			)
			(layer "B.SilkS")
		)
		(fp_line
			(start 0.7874 -0.4064)
			(end -0.7874 -0.4064)
			(stroke
				(width 0.1524)
				(type default)
			)
			(layer "B.SilkS")
		)
		(fp_line
			(start -0.67945 0.3048)
			(end -0.120396 0.3048)
			(stroke
				(width 0.1)
				(type default)
			)
			(layer "B.Fab")
		)
		(fp_line
			(start -0.120396 0.3048)
			(end -0.120396 0.2794)
			(stroke
				(width 0.1)
				(type default)
			)
			(layer "B.Fab")
		)
		(fp_line
			(start 0.12065 0.3048)
			(end 0.67945 0.3048)
			(stroke
				(width 0.1)
				(type default)
			)
			(layer "B.Fab")
		)
		(fp_line
			(start 0.67945 0.3048)
			(end 0.67945 -0.305054)
			(stroke
				(width 0.1)
				(type default)
			)
			(layer "B.Fab")
		)
		(fp_line
			(start -0.120396 0.2794)
			(end 0.12065 0.2794)
			(stroke
				(width 0.1)
				(type default)
			)
			(layer "B.Fab")
		)
		(fp_line
			(start 0.12065 0.2794)
			(end 0.12065 0.3048)
			(stroke
				(width 0.1)
				(type default)
			)
			(layer "B.Fab")
		)
		(fp_line
			(start -0.12065 -0.2794)
			(end -0.12065 -0.3048)
			(stroke
				(width 0.1)
				(type default)
			)
			(layer "B.Fab")
		)
		(fp_line
			(start 0.12065 -0.2794)
			(end -0.12065 -0.2794)
			(stroke
				(width 0.1)
				(type default)
			)
			(layer "B.Fab")
		)
		(fp_line
			(start -0.67945 -0.3048)
			(end -0.67945 0.3048)
			(stroke
				(width 0.1)
				(type default)
			)
			(layer "B.Fab")
		)
		(fp_line
			(start -0.12065 -0.3048)
			(end -0.67945 -0.3048)
			(stroke
				(width 0.1)
				(type default)
			)
			(layer "B.Fab")
		)
		(fp_line
			(start 0.12065 -0.305054)
			(end 0.12065 -0.2794)
			(stroke
				(width 0.1)
				(type default)
			)
			(layer "B.Fab")
		)
		(fp_line
			(start 0.67945 -0.305054)
			(end 0.12065 -0.305054)
			(stroke
				(width 0.1)
				(type default)
			)
			(layer "B.Fab")
		)
		(pad "1" smd circle
			(at 0.40005 0 90)
			(size 0 0)
			(layers "B.Cu" "B.Mask" "B.Paste")
			(net "P3V3_9ZXL045_P0_VDD")
		)
		(pad "2" smd circle
			(at -0.40005 0 90)
			(size 0 0)
			(layers "B.Cu" "B.Mask" "B.Paste")
			(net "GND")
		)
	)
	(footprint ""
		(layer "B.Cu")
		(at 17.779492 -97.342198 90)
		(property "Reference" "C2040"
			(at 0 0 90)
			(layer "B.SilkS")
			(hide yes)
			(effects
				(font
					(size 1.27 1.27)
				)
				(justify mirror)
			)
		)
		(property "Value" ""
			(at 0 0 90)
			(layer "B.Fab")
			(effects
				(font
					(size 1.27 1.27)
				)
				(justify mirror)
			)
		)
		(duplicate_pad_numbers_are_jumpers no)
		(fp_line
			(start 0.7874 -0.4064)
			(end -0.7874 -0.4064)
			(stroke
				(width 0.1524)
				(type default)
			)
			(layer "B.SilkS")
		)
		(fp_line
			(start -0.7874 -0.4064)
			(end -0.7874 0.4064)
			(stroke
				(width 0.1524)
				(type default)
			)
			(layer "B.SilkS")
		)
		(fp_line
			(start 0.7874 0.4064)
			(end 0.7874 -0.4064)
			(stroke
				(width 0.1524)
				(type default)
			)
			(layer "B.SilkS")
		)
		(fp_line
			(start -0.7874 0.4064)
			(end 0.7874 0.4064)
			(stroke
				(width 0.1524)
				(type default)
			)
			(layer "B.SilkS")
		)
		(fp_line
			(start 0.67945 -0.305054)
			(end 0.12065 -0.305054)
			(stroke
				(width 0.1)
				(type default)
			)
			(layer "B.Fab")
		)
		(fp_line
			(start 0.12065 -0.305054)
			(end 0.12065 -0.2794)
			(stroke
				(width 0.1)
				(type default)
			)
			(layer "B.Fab")
		)
		(fp_line
			(start -0.12065 -0.3048)
			(end -0.67945 -0.3048)
			(stroke
				(width 0.1)
				(type default)
			)
			(layer "B.Fab")
		)
		(fp_line
			(start -0.67945 -0.3048)
			(end -0.67945 0.3048)
			(stroke
				(width 0.1)
				(type default)
			)
			(layer "B.Fab")
		)
		(fp_line
			(start 0.12065 -0.2794)
			(end -0.12065 -0.2794)
			(stroke
				(width 0.1)
				(type default)
			)
			(layer "B.Fab")
		)
		(fp_line
			(start -0.12065 -0.2794)
			(end -0.12065 -0.3048)
			(stroke
				(width 0.1)
				(type default)
			)
			(layer "B.Fab")
		)
		(fp_line
			(start 0.12065 0.2794)
			(end 0.12065 0.3048)
			(stroke
				(width 0.1)
				(type default)
			)
			(layer "B.Fab")
		)
		(fp_line
			(start -0.120396 0.2794)
			(end 0.12065 0.2794)
			(stroke
				(width 0.1)
				(type default)
			)
			(layer "B.Fab")
		)
		(fp_line
			(start 0.67945 0.3048)
			(end 0.67945 -0.305054)
			(stroke
				(width 0.1)
				(type default)
			)
			(layer "B.Fab")
		)
		(fp_line
			(start 0.12065 0.3048)
			(end 0.67945 0.3048)
			(stroke
				(width 0.1)
				(type default)
			)
			(layer "B.Fab")
		)
		(fp_line
			(start -0.120396 0.3048)
			(end -0.120396 0.2794)
			(stroke
				(width 0.1)
				(type default)
			)
			(layer "B.Fab")
		)
		(fp_line
			(start -0.67945 0.3048)
			(end -0.120396 0.3048)
			(stroke
				(width 0.1)
				(type default)
			)
			(layer "B.Fab")
		)
		(pad "1" smd circle
			(at 0.40005 0 270)
			(size 0 0)
			(layers "B.Cu" "B.Mask" "B.Paste")
			(net "P3V3_AUX_USB_HUB")
		)
		(pad "2" smd circle
			(at -0.40005 0 270)
			(size 0 0)
			(layers "B.Cu" "B.Mask" "B.Paste")
			(net "GND")
		)
	)
	(footprint ""
		(layer "B.Cu")
		(at 331.793342 -392.1252 180)
		(property "Reference" "R1022"
			(at 0 0 0)
			(layer "B.SilkS")
			(hide yes)
			(effects
				(font
					(size 1.27 1.27)
				)
				(justify mirror)
			)
		)
		(property "Value" ""
			(at 0 0 0)
			(layer "B.Fab")
			(effects
				(font
					(size 1.27 1.27)
				)
				(justify mirror)
			)
		)
		(duplicate_pad_numbers_are_jumpers no)
		(fp_line
			(start 0.32512 0.175006)
			(end 0.32512 -0.175006)
			(stroke
				(width 0.1)
				(type default)
			)
			(layer "B.Fab")
		)
		(fp_line
			(start 0.32512 -0.175006)
			(end -0.32512 -0.175006)
			(stroke
				(width 0.1)
				(type default)
			)
			(layer "B.Fab")
		)
		(fp_line
			(start -0.32512 0.175006)
			(end 0.32512 0.175006)
			(stroke
				(width 0.1)
				(type default)
			)
			(layer "B.Fab")
		)
		(fp_line
			(start -0.32512 -0.175006)
			(end -0.32512 0.175006)
			(stroke
				(width 0.1)
				(type default)
			)
			(layer "B.Fab")
		)
		(pad "1" smd rect
			(at 0.2667 0)
			(size 0.3048 0.381)
			(layers "B.Cu" "B.Mask" "B.Paste")
			(net "RT_CPU0_P1_SCAN_MODE")
		)
		(pad "2" smd rect
			(at -0.2667 0 180)
			(size 0.3048 0.381)
			(layers "B.Cu" "B.Mask" "B.Paste")
			(net "GND")
		)
	)
)
